# BASEBOARD_FAB2 (Tioga Pass) — schematic netlist excerpt (pin names and nets, part order shuffled) for the footprints in the layout excerpt that follows; sources: Cadence DE-HDL packaged netlist, KiCad conversion of Wiwynn_Tioga_Pass_MB.brd

R3M1  RES  0.0 5% CHIP  pkg 0402  page 218 : A = P3V3_STBY ; B = VR_PVDDQ_DEF_VDD
R4E13  RES  100.0 1% CHIP  pkg 0603  page 203 : A = PVCCIN_CPU0 ; B = GND
R25W101  RES  4.75K 1% EMPTY  pkg 0402  page 150 : A = P3V3_STBY ; B = BMC_STRAP_BIT17

(kicad_pcb
	(version 20260206)
	(generator "pcbnew")
	(generator_version "10.0")
	(general
		(thickness 1.6)
		(legacy_teardrops no)
	)
	(paper "A4")
	(title_block
		(title "Wiwynn_Tioga_Pass_MB.brd")
		(comment 1 "Tioga Pass / footprints 599-601 of 4770")
	)
	(layers
		(0 "F.Cu" signal "TOP")
		(4 "In1.Cu" signal "L2GND")
		(6 "In2.Cu" signal "L3")
		(8 "In3.Cu" signal "L4GND")
		(10 "In4.Cu" signal "L5")
		(12 "In5.Cu" signal "L6GND")
		(14 "In6.Cu" signal "L7VCC")
		(16 "In7.Cu" signal "L8VCC")
		(18 "In8.Cu" signal "L9GND")
		(20 "In9.Cu" signal "L10")
		(22 "In10.Cu" signal "L11GND")
		(24 "In11.Cu" signal "L12")
		(26 "In12.Cu" signal "L13GND")
		(2 "B.Cu" signal "BOTTOM")
		(9 "F.Adhes" user "F.Adhesive")
		(11 "B.Adhes" user "B.Adhesive")
		(13 "F.Paste" user "Package Geometry/Pastemask Top")
		(15 "B.Paste" user "Package Geometry/Pastemask Bottom")
		(5 "F.SilkS" user "Ref Des/Silkscreen Top")
		(7 "B.SilkS" user "Ref Des/Silkscreen Bottom")
		(1 "F.Mask" user "Board Geometry/Soldermask Top")
		(3 "B.Mask" user "Board Geometry/Soldermask Bottom")
		(17 "Dwgs.User" user "User.Drawings")
		(19 "Cmts.User" user "User.Comments")
		(21 "Eco1.User" user "User.Eco1")
		(23 "Eco2.User" user "User.Eco2")
		(25 "Edge.Cuts" user "Board Geometry/Outline")
		(27 "Margin" user)
		(31 "F.CrtYd" user "Package Geometry/Place Bound Top")
		(29 "B.CrtYd" user "Package Geometry/Place Bound Bottom")
		(35 "F.Fab" user "Ref Des/Assembly Top")
		(33 "B.Fab" user "Ref Des/Assembly Bottom")
	)
	(footprint ""
		(layer "F.Cu")
		(at 209.296 -52.79898 -90)
		(property "Reference" "R4E13"
			(at 0 0 270)
			(layer "F.SilkS")
			(hide yes)
			(effects
				(font
					(size 1.27 1.27)
				)
			)
		)
		(property "Value" ""
			(at 0 0 270)
			(layer "F.Fab")
			(effects
				(font
					(size 1.27 1.27)
				)
			)
		)
		(duplicate_pad_numbers_are_jumpers no)
		(fp_poly
			(pts
				(xy -0.4953 -0.2032) (xy 0.4953 -0.2032) (xy 0.4953 1.6002) (xy -0.4953 1.6002)
			)
			(stroke
				(width 0)
				(type default)
			)
			(fill no)
			(layer "F.CrtYd")
		)
		(fp_line
			(start -0.4953 1.6002)
			(end -0.4953 -0.2032)
			(stroke
				(width 0.1)
				(type default)
			)
			(layer "F.Fab")
		)
		(fp_line
			(start 0.4953 1.6002)
			(end -0.4953 1.6002)
			(stroke
				(width 0.1)
				(type default)
			)
			(layer "F.Fab")
		)
		(fp_line
			(start -0.4953 -0.2032)
			(end 0.4953 -0.2032)
			(stroke
				(width 0.1)
				(type default)
			)
			(layer "F.Fab")
		)
		(fp_line
			(start 0.4953 -0.2032)
			(end 0.4953 1.6002)
			(stroke
				(width 0.1)
				(type default)
			)
			(layer "F.Fab")
		)
		(pad "1" smd rect
			(at 0 0 270)
			(size 0.762 0.889)
			(layers "F.Cu" "F.Mask" "F.Paste")
			(net "PVCCIN_CPU0")
		)
		(pad "2" smd rect
			(at 0 1.397 270)
			(size 0.762 0.889)
			(layers "F.Cu" "F.Mask" "F.Paste")
			(net "GND")
		)
		(zone
			(layer "F.Cu")
			(hatch none 0.5)
			(connect_pads
				(clearance 0)
			)
			(min_thickness 0.25)
			(keepout
				(tracks not_allowed)
				(vias allowed)
				(pads allowed)
				(copperpour not_allowed)
				(footprints allowed)
			)
			(placement
				(enabled no)
				(sheetname "")
			)
			(fill
				(thermal_gap 0.5)
				(thermal_bridge_width 0.5)
				(island_removal_mode 0)
			)
			(polygon
				(pts
					(xy 208.3435 -53.17998) (xy 208.3435 -52.41798) (xy 208.8515 -52.41798) (xy 208.8515 -53.17998)
				)
			)
		)
		(zone
			(layer "F.Cu")
			(hatch none 0.5)
			(connect_pads
				(clearance 0)
			)
			(min_thickness 0.25)
			(keepout
				(tracks allowed)
				(vias not_allowed)
				(pads allowed)
				(copperpour not_allowed)
				(footprints allowed)
			)
			(placement
				(enabled no)
				(sheetname "")
			)
			(fill
				(thermal_gap 0.5)
				(thermal_bridge_width 0.5)
				(island_removal_mode 0)
			)
			(polygon
				(pts
					(xy 208.3435 -52.41798) (xy 208.8515 -52.41798) (xy 208.8515 -53.17998) (xy 208.3435 -53.17998)
				)
			)
		)
	)
	(footprint ""
		(layer "F.Cu")
		(at 420.103046 -48.968152)
		(property "Reference" "R25W101"
			(at -0.8382 -0.67818 0)
			(unlocked yes)
			(layer "F.SilkS")
			(effects
				(font
					(size 0.4064 0.254)
					(thickness 0.1524)
				)
				(justify left)
			)
		)
		(property "Value" ""
			(at 0 0 0)
			(layer "F.Fab")
			(effects
				(font
					(size 1.27 1.27)
				)
			)
		)
		(duplicate_pad_numbers_are_jumpers no)
		(fp_poly
			(pts
				(xy -0.2794 -0.1016) (xy 0.2794 -0.1016) (xy 0.2794 0.9906) (xy -0.2794 0.9906)
			)
			(stroke
				(width 0)
				(type default)
			)
			(fill no)
			(layer "F.CrtYd")
		)
		(fp_line
			(start -0.2794 -0.1016)
			(end -0.2794 0.9906)
			(stroke
				(width 0.1)
				(type default)
			)
			(layer "F.Fab")
		)
		(fp_line
			(start -0.2794 0.9906)
			(end 0.2794 0.9906)
			(stroke
				(width 0.1)
				(type default)
			)
			(layer "F.Fab")
		)
		(fp_line
			(start 0.2794 -0.1016)
			(end -0.2794 -0.1016)
			(stroke
				(width 0.1)
				(type default)
			)
			(layer "F.Fab")
		)
		(fp_line
			(start 0.2794 0.9906)
			(end 0.2794 -0.1016)
			(stroke
				(width 0.1)
				(type default)
			)
			(layer "F.Fab")
		)
		(pad "1" smd rect
			(at 0 0)
			(size 0.508 0.508)
			(layers "F.Cu" "F.Mask" "F.Paste")
			(net "P3V3_STBY")
		)
		(pad "2" smd rect
			(at 0 0.889)
			(size 0.508 0.508)
			(layers "F.Cu" "F.Mask" "F.Paste")
			(net "BMC_STRAP_BIT17")
		)
		(zone
			(layer "F.Cu")
			(hatch none 0.5)
			(connect_pads
				(clearance 0)
			)
			(min_thickness 0.25)
			(keepout
				(tracks allowed)
				(vias not_allowed)
				(pads allowed)
				(copperpour not_allowed)
				(footprints allowed)
			)
			(placement
				(enabled no)
				(sheetname "")
			)
			(fill
				(thermal_gap 0.5)
				(thermal_bridge_width 0.5)
				(island_removal_mode 0)
			)
			(polygon
				(pts
					(xy 419.849046 -48.714152) (xy 420.357046 -48.714152) (xy 420.357046 -48.333152) (xy 419.849046 -48.333152)
				)
			)
		)
		(zone
			(layer "F.Cu")
			(hatch none 0.5)
			(connect_pads
				(clearance 0)
			)
			(min_thickness 0.25)
			(keepout
				(tracks not_allowed)
				(vias allowed)
				(pads allowed)
				(copperpour not_allowed)
				(footprints allowed)
			)
			(placement
				(enabled no)
				(sheetname "")
			)
			(fill
				(thermal_gap 0.5)
				(thermal_bridge_width 0.5)
				(island_removal_mode 0)
			)
			(polygon
				(pts
					(xy 419.849046 -48.333152) (xy 420.357046 -48.333152) (xy 420.357046 -48.714152) (xy 419.849046 -48.714152)
				)
			)
		)
	)
	(footprint ""
		(layer "F.Cu")
		(at 353.387914 -134.222744 180)
		(property "Reference" "R3M1"
			(at 0 0 180)
			(layer "F.SilkS")
			(hide yes)
			(effects
				(font
					(size 1.27 1.27)
				)
			)
		)
		(property "Value" ""
			(at 0 0 180)
			(layer "F.Fab")
			(effects
				(font
					(size 1.27 1.27)
				)
			)
		)
		(duplicate_pad_numbers_are_jumpers no)
		(fp_rect
			(start -0.2794 -0.1016)
			(end 0.2794 0.9906)
			(stroke
				(width 0)
				(type default)
			)
			(fill no)
			(layer "F.CrtYd")
		)
		(fp_line
			(start 0.2794 0.9906)
			(end 0.2794 -0.1016)
			(stroke
				(width 0.1)
				(type default)
			)
			(layer "F.Fab")
		)
		(fp_line
			(start 0.2794 -0.1016)
			(end -0.2794 -0.1016)
			(stroke
				(width 0.1)
				(type default)
			)
			(layer "F.Fab")
		)
		(fp_line
			(start -0.2794 0.9906)
			(end 0.2794 0.9906)
			(stroke
				(width 0.1)
				(type default)
			)
			(layer "F.Fab")
		)
		(fp_line
			(start -0.2794 -0.1016)
			(end -0.2794 0.9906)
			(stroke
				(width 0.1)
				(type default)
			)
			(layer "F.Fab")
		)
		(pad "1" smd rect
			(at 0 0 180)
			(size 0.508 0.508)
			(layers "F.Cu" "F.Mask" "F.Paste")
			(net "P3V3_STBY")
		)
		(pad "2" smd rect
			(at 0 0.889 180)
			(size 0.508 0.508)
			(layers "F.Cu" "F.Mask" "F.Paste")
			(net "VR_PVDDQ_DEF_VDD")
		)
		(zone
			(layer "F.Cu")
			(hatch none 0.5)
			(connect_pads
				(clearance 0)
			)
			(min_thickness 0.25)
			(keepout
				(tracks allowed)
				(vias not_allowed)
				(pads allowed)
				(copperpour not_allowed)
				(footprints allowed)
			)
			(placement
				(enabled no)
				(sheetname "")
			)
			(fill
				(thermal_gap 0.5)
				(thermal_bridge_width 0.5)
				(island_removal_mode 0)
			)
			(polygon
				(pts
					(xy 353.641914 -134.476744) (xy 353.641914 -134.857744) (xy 353.133914 -134.857744) (xy 353.133914 -134.476744)
				)
			)
		)
		(zone
			(layer "F.Cu")
			(hatch none 0.5)
			(connect_pads
				(clearance 0)
			)
			(min_thickness 0.25)
			(keepout
				(tracks not_allowed)
				(vias allowed)
				(pads allowed)
				(copperpour not_allowed)
				(footprints allowed)
			)
			(placement
				(enabled no)
				(sheetname "")
			)
			(fill
				(thermal_gap 0.5)
				(thermal_bridge_width 0.5)
				(island_removal_mode 0)
			)
			(polygon
				(pts
					(xy 353.641914 -134.476744) (xy 353.641914 -134.857744) (xy 353.133914 -134.857744) (xy 353.133914 -134.476744)
				)
			)
		)
	)
)
